# SCM (Grand Teton) — schematic netlist excerpt (pin names and nets, part order shuffled) for the footprints in the layout excerpt that follows; sources: Cadence DE-HDL packaged netlist, KiCad conversion of 12092022_DA0F0TMDCD0_F0T_Management_Board_D_brd_V3_OCP.brd

C274  Q_CAP  0.1UF 25V 10% X7R  pkg 0402  page 49 : A = P3V3_AUX ; B = GND
R364  Q_RES  120 1% CHIP  pkg 0402LF  page 20 : A = M_BMC_DDR4_MA<13> ; B = P1V2_AUX

(kicad_pcb
	(version 20260206)
	(generator "pcbnew")
	(generator_version "10.0")
	(general
		(thickness 1.6)
		(legacy_teardrops no)
	)
	(paper "A4")
	(title_block
		(title "12092022_DA0F0TMDCD0_F0T_Management_Board_D_brd_V3_OCP.brd")
		(comment 1 "Grand Teton / footprints 1155-1156 of 1440")
	)
	(layers
		(0 "F.Cu" signal "TOP")
		(4 "In1.Cu" signal "GND")
		(6 "In2.Cu" signal "IN1")
		(8 "In3.Cu" signal "GND1")
		(10 "In4.Cu" signal "IN2")
		(12 "In5.Cu" signal "VCC")
		(14 "In6.Cu" signal "VCC1")
		(16 "In7.Cu" signal "IN3")
		(18 "In8.Cu" signal "GND2")
		(20 "In9.Cu" signal "IN4")
		(22 "In10.Cu" signal "GND3")
		(2 "B.Cu" signal "BOTTOM")
		(9 "F.Adhes" user "F.Adhesive")
		(11 "B.Adhes" user "B.Adhesive")
		(13 "F.Paste" user "Package Geometry/Pastemask Top")
		(15 "B.Paste" user "Package Geometry/Pastemask Bottom")
		(5 "F.SilkS" user "Ref Des/Silkscreen Top")
		(7 "B.SilkS" user "Ref Des/Silkscreen Bottom")
		(1 "F.Mask" user "Board Geometry/Soldermask Top")
		(3 "B.Mask" user "Board Geometry/Soldermask Bottom")
		(17 "Dwgs.User" user "User.Drawings")
		(19 "Cmts.User" user "User.Comments")
		(21 "Eco1.User" user "User.Eco1")
		(23 "Eco2.User" user "User.Eco2")
		(25 "Edge.Cuts" user "Board Geometry/Outline")
		(27 "Margin" user)
		(31 "F.CrtYd" user "Package Geometry/Place Bound Top")
		(29 "B.CrtYd" user "Package Geometry/Place Bound Bottom")
		(35 "F.Fab" user "Ref Des/Assembly Top")
		(33 "B.Fab" user "Ref Des/Assembly Bottom")
	)
	(footprint ""
		(layer "B.Cu")
		(at 15.24 -26.67 -90)
		(property "Reference" "C274"
			(at 0 0 90)
			(layer "B.SilkS")
			(hide yes)
			(effects
				(font
					(size 1.27 1.27)
				)
				(justify mirror)
			)
		)
		(property "Value" ""
			(at 0 0 90)
			(layer "B.Fab")
			(effects
				(font
					(size 1.27 1.27)
				)
				(justify mirror)
			)
		)
		(duplicate_pad_numbers_are_jumpers no)
		(fp_line
			(start -0.7874 0.4064)
			(end 0.7874 0.4064)
			(stroke
				(width 0.1524)
				(type default)
			)
			(layer "B.SilkS")
		)
		(fp_line
			(start 0.7874 0.4064)
			(end 0.7874 -0.4064)
			(stroke
				(width 0.1524)
				(type default)
			)
			(layer "B.SilkS")
		)
		(fp_line
			(start -0.7874 -0.4064)
			(end -0.7874 0.4064)
			(stroke
				(width 0.1524)
				(type default)
			)
			(layer "B.SilkS")
		)
		(fp_line
			(start 0.7874 -0.4064)
			(end -0.7874 -0.4064)
			(stroke
				(width 0.1524)
				(type default)
			)
			(layer "B.SilkS")
		)
		(fp_line
			(start -0.67945 0.3048)
			(end -0.120396 0.3048)
			(stroke
				(width 0.1)
				(type default)
			)
			(layer "B.Fab")
		)
		(fp_line
			(start -0.120396 0.3048)
			(end -0.120396 0.2794)
			(stroke
				(width 0.1)
				(type default)
			)
			(layer "B.Fab")
		)
		(fp_line
			(start 0.12065 0.3048)
			(end 0.67945 0.3048)
			(stroke
				(width 0.1)
				(type default)
			)
			(layer "B.Fab")
		)
		(fp_line
			(start 0.67945 0.3048)
			(end 0.67945 -0.305054)
			(stroke
				(width 0.1)
				(type default)
			)
			(layer "B.Fab")
		)
		(fp_line
			(start -0.120396 0.2794)
			(end 0.12065 0.2794)
			(stroke
				(width 0.1)
				(type default)
			)
			(layer "B.Fab")
		)
		(fp_line
			(start 0.12065 0.2794)
			(end 0.12065 0.3048)
			(stroke
				(width 0.1)
				(type default)
			)
			(layer "B.Fab")
		)
		(fp_line
			(start -0.12065 -0.2794)
			(end -0.12065 -0.3048)
			(stroke
				(width 0.1)
				(type default)
			)
			(layer "B.Fab")
		)
		(fp_line
			(start 0.12065 -0.2794)
			(end -0.12065 -0.2794)
			(stroke
				(width 0.1)
				(type default)
			)
			(layer "B.Fab")
		)
		(fp_line
			(start -0.67945 -0.3048)
			(end -0.67945 0.3048)
			(stroke
				(width 0.1)
				(type default)
			)
			(layer "B.Fab")
		)
		(fp_line
			(start -0.12065 -0.3048)
			(end -0.67945 -0.3048)
			(stroke
				(width 0.1)
				(type default)
			)
			(layer "B.Fab")
		)
		(fp_line
			(start 0.12065 -0.305054)
			(end 0.12065 -0.2794)
			(stroke
				(width 0.1)
				(type default)
			)
			(layer "B.Fab")
		)
		(fp_line
			(start 0.67945 -0.305054)
			(end 0.12065 -0.305054)
			(stroke
				(width 0.1)
				(type default)
			)
			(layer "B.Fab")
		)
		(pad "1" smd circle
			(at 0.40005 0 90)
			(size 0 0)
			(layers "B.Cu" "B.Mask" "B.Paste")
			(net "P3V3_AUX")
		)
		(pad "2" smd circle
			(at -0.40005 0 90)
			(size 0 0)
			(layers "B.Cu" "B.Mask" "B.Paste")
			(net "GND")
		)
	)
	(footprint ""
		(layer "B.Cu")
		(at 85.29955 -41.379394 180)
		(property "Reference" "R364"
			(at 0 0 0)
			(layer "B.SilkS")
			(hide yes)
			(effects
				(font
					(size 1.27 1.27)
				)
				(justify mirror)
			)
		)
		(property "Value" ""
			(at 0 0 0)
			(layer "B.Fab")
			(effects
				(font
					(size 1.27 1.27)
				)
				(justify mirror)
			)
		)
		(duplicate_pad_numbers_are_jumpers no)
		(fp_line
			(start 0.7874 0.4064)
			(end 0.7874 -0.4064)
			(stroke
				(width 0.1524)
				(type default)
			)
			(layer "B.SilkS")
		)
		(fp_line
			(start 0.7874 -0.4064)
			(end -0.7874 -0.4064)
			(stroke
				(width 0.1524)
				(type default)
			)
			(layer "B.SilkS")
		)
		(fp_line
			(start -0.7874 0.4064)
			(end 0.7874 0.4064)
			(stroke
				(width 0.1524)
				(type default)
			)
			(layer "B.SilkS")
		)
		(fp_line
			(start -0.7874 -0.4064)
			(end -0.7874 0.4064)
			(stroke
				(width 0.1524)
				(type default)
			)
			(layer "B.SilkS")
		)
		(fp_line
			(start 0.67945 0.3048)
			(end 0.67945 -0.305054)
			(stroke
				(width 0.1)
				(type default)
			)
			(layer "B.Fab")
		)
		(fp_line
			(start 0.67945 -0.305054)
			(end 0.12065 -0.305054)
			(stroke
				(width 0.1)
				(type default)
			)
			(layer "B.Fab")
		)
		(fp_line
			(start 0.12065 0.3048)
			(end 0.67945 0.3048)
			(stroke
				(width 0.1)
				(type default)
			)
			(layer "B.Fab")
		)
		(fp_line
			(start 0.12065 0.2794)
			(end 0.12065 0.3048)
			(stroke
				(width 0.1)
				(type default)
			)
			(layer "B.Fab")
		)
		(fp_line
			(start 0.12065 -0.2794)
			(end -0.12065 -0.2794)
			(stroke
				(width 0.1)
				(type default)
			)
			(layer "B.Fab")
		)
		(fp_line
			(start 0.12065 -0.305054)
			(end 0.12065 -0.2794)
			(stroke
				(width 0.1)
				(type default)
			)
			(layer "B.Fab")
		)
		(fp_line
			(start -0.120396 0.3048)
			(end -0.120396 0.2794)
			(stroke
				(width 0.1)
				(type default)
			)
			(layer "B.Fab")
		)
		(fp_line
			(start -0.120396 0.2794)
			(end 0.12065 0.2794)
			(stroke
				(width 0.1)
				(type default)
			)
			(layer "B.Fab")
		)
		(fp_line
			(start -0.12065 -0.2794)
			(end -0.12065 -0.3048)
			(stroke
				(width 0.1)
				(type default)
			)
			(layer "B.Fab")
		)
		(fp_line
			(start -0.12065 -0.3048)
			(end -0.67945 -0.3048)
			(stroke
				(width 0.1)
				(type default)
			)
			(layer "B.Fab")
		)
		(fp_line
			(start -0.67945 0.3048)
			(end -0.120396 0.3048)
			(stroke
				(width 0.1)
				(type default)
			)
			(layer "B.Fab")
		)
		(fp_line
			(start -0.67945 -0.3048)
			(end -0.67945 0.3048)
			(stroke
				(width 0.1)
				(type default)
			)
			(layer "B.Fab")
		)
		(pad "1" smd circle
			(at 0.40005 0)
			(size 0 0)
			(layers "B.Cu" "B.Mask" "B.Paste")
			(net "M_BMC_DDR4_MA<13>")
		)
		(pad "2" smd circle
			(at -0.40005 0)
			(size 0 0)
			(layers "B.Cu" "B.Mask" "B.Paste")
			(net "P1V2_AUX")
		)
	)
)
